(kicad_pcb
	(version 20241229)
	(generator "pcbnew")
	(generator_version "9.0")
	(general
		(thickness 1.6)
		(legacy_teardrops no)
	)
	(paper "A4")
	(title_block
		(title "OCuLink to PCIe adapter")
		(date "2025-06-18")
		(rev "1.0.0")
		(company "Antmicro Ltd")
		(comment 1 "www.antmicro.com")
		(comment 9 "footprint 156 of 159 (J2), pads 88-168 of 168")
	)
	(layers
		(0 "F.Cu" signal)
		(4 "In1.Cu" signal)
		(6 "In2.Cu" signal)
		(2 "B.Cu" signal)
		(9 "F.Adhes" user "F.Adhesive")
		(11 "B.Adhes" user "B.Adhesive")
		(13 "F.Paste" user)
		(15 "B.Paste" user)
		(5 "F.SilkS" user "F.Silkscreen")
		(7 "B.SilkS" user "B.Silkscreen")
		(1 "F.Mask" user)
		(3 "B.Mask" user)
		(17 "Dwgs.User" user "User.Drawings")
		(19 "Cmts.User" user "User.Comments")
		(21 "Eco1.User" user "User.Eco1")
		(23 "Eco2.User" user "User.Eco2")
		(25 "Edge.Cuts" user)
		(27 "Margin" user)
		(31 "F.CrtYd" user "F.Courtyard")
		(29 "B.CrtYd" user "B.Courtyard")
		(35 "F.Fab" user)
		(33 "B.Fab" user)
	)
	(footprint "antmicro-footprints:AMPHENOL_10146070-113Y0LF"
		(locked yes)
		(layer "F.Cu")
		(at 111.674 79.6 90)
		(property "Reference" "J2"
			(at 41.1 5.926 90)
			(layer "F.SilkS")
			(effects
				(font
					(size 0.7 0.7)
					(thickness 0.15)
				)
				(justify left bottom)
			)
		)
		(property "Value" "PCIe_x16_10146070-113Y0LF-vertical"
			(at -28.471 6.61 90)
			(layer "F.Fab")
			(effects
				(font
					(size 0.7 0.7)
					(thickness 0.15)
				)
				(justify left bottom)
			)
		)
		(property "Datasheet" "https://www.farnell.com/datasheets/3212936.pdf"
			(at 0 0 90)
			(layer "F.Fab")
			(hide yes)
			(effects
				(font
					(size 1.27 1.27)
					(thickness 0.15)
				)
			)
		)
		(property "Description" "164 Position Female Connector PCI Express™ Gold 0.039\" (1.00mm) Black"
			(at 0 0 90)
			(layer "F.Fab")
			(hide yes)
			(effects
				(font
					(size 1.27 1.27)
					(thickness 0.15)
				)
			)
		)
		(property "PARTREV" "E"
			(at 0 0 90)
			(unlocked yes)
			(layer "F.Fab")
			(hide yes)
			(effects
				(font
					(size 1 1)
					(thickness 0.15)
				)
			)
		)
		(property "STANDARD" "Manufacturer Recommendations"
			(at 0 0 90)
			(unlocked yes)
			(layer "F.Fab")
			(hide yes)
			(effects
				(font
					(size 1 1)
					(thickness 0.15)
				)
			)
		)
		(property "MAXIMUM_PACKAGE_HEIGHT" "11.25mm"
			(at 0 0 90)
			(unlocked yes)
			(layer "F.Fab")
			(hide yes)
			(effects
				(font
					(size 1 1)
					(thickness 0.15)
				)
			)
		)
		(property "Manufacturer" "Amphenol"
			(at 0 0 90)
			(unlocked yes)
			(layer "F.Fab")
			(hide yes)
			(effects
				(font
					(size 1 1)
					(thickness 0.15)
				)
			)
		)
		(property "Author" "Antmicro"
			(at 0 0 90)
			(unlocked yes)
			(layer "F.Fab")
			(hide yes)
			(effects
				(font
					(size 1 1)
					(thickness 0.15)
				)
			)
		)
		(property "License" "Apache-2.0"
			(at 0 0 90)
			(unlocked yes)
			(layer "F.Fab")
			(hide yes)
			(effects
				(font
					(size 1 1)
					(thickness 0.15)
				)
			)
		)
		(property "MPN" "10146070-113Y0LF"
			(at 0 0 90)
			(unlocked yes)
			(layer "F.Fab")
			(hide yes)
			(effects
				(font
					(size 1 1)
					(thickness 0.15)
				)
			)
		)
		(sheetname "/PCIe-connector/")
		(sheetfile "pcie-connector.kicad_sch")
		(attr smd)
		(pad "B4" smd rect
			(at -38.5 3.1 90)
			(size 0.53 2)
			(layers "F.Cu" "F.Mask" "F.Paste")
			(net 66 "GND")
			(pinfunction "B4")
			(pintype "passive")
		)
		(pad "B5" smd rect
			(at -37.5 3.1 90)
			(size 0.53 2)
			(layers "F.Cu" "F.Mask" "F.Paste")
			(net 102 "/OCuLink/I2C0.SCL")
			(pinfunction "B5")
			(pintype "passive")
		)
		(pad "B6" smd rect
			(at -36.5 3.1 90)
			(size 0.53 2)
			(layers "F.Cu" "F.Mask" "F.Paste")
			(net 103 "/OCuLink/I2C0.SDA")
			(pinfunction "B6")
			(pintype "passive")
		)
		(pad "B7" smd rect
			(at -35.5 3.1 90)
			(size 0.53 2)
			(layers "F.Cu" "F.Mask" "F.Paste")
			(net 66 "GND")
			(pinfunction "B7")
			(pintype "passive")
		)
		(pad "B8" smd rect
			(at -34.5 3.1 90)
			(size 0.53 2)
			(layers "F.Cu" "F.Mask" "F.Paste")
			(net 134 "+3V3")
			(pinfunction "B8")
			(pintype "passive")
		)
		(pad "B9" smd rect
			(at -33.5 3.1 90)
			(size 0.53 2)
			(layers "F.Cu" "F.Mask" "F.Paste")
			(net 50 "unconnected-(J2-PadB9)")
			(pinfunction "B9")
			(pintype "passive+no_connect")
		)
		(pad "B10" smd rect
			(at -32.5 3.1 90)
			(size 0.53 2)
			(layers "F.Cu" "F.Mask" "F.Paste")
			(net 83 "/PCIe-connector/3V3_PCIe_AUX")
			(pinfunction "B10")
			(pintype "passive")
		)
		(pad "B11" smd rect
			(at -31.5 3.1 90)
			(size 0.53 2)
			(layers "F.Cu" "F.Mask" "F.Paste")
			(net 93 "/OCuLink/~{WAKE}")
			(pinfunction "B11")
			(pintype "passive")
		)
		(pad "B12" smd rect
			(at -28.5 3.1 90)
			(size 0.53 2)
			(layers "F.Cu" "F.Mask" "F.Paste")
			(net 38 "unconnected-(J2-PadB12)")
			(pinfunction "B12")
			(pintype "passive+no_connect")
		)
		(pad "B13" smd rect
			(at -27.5 3.1 90)
			(size 0.53 2)
			(layers "F.Cu" "F.Mask" "F.Paste")
			(net 66 "GND")
			(pinfunction "B13")
			(pintype "passive")
		)
		(pad "B14" smd rect
			(at -26.5 3.1 90)
			(size 0.53 2)
			(layers "F.Cu" "F.Mask" "F.Paste")
			(net 72 "/OCuLink/PCIe_{x4}.TX0+")
			(pinfunction "B14")
			(pintype "passive")
		)
		(pad "B15" smd rect
			(at -25.5 3.1 90)
			(size 0.53 2)
			(layers "F.Cu" "F.Mask" "F.Paste")
			(net 74 "/OCuLink/PCIe_{x4}.TX0-")
			(pinfunction "B15")
			(pintype "passive")
		)
		(pad "B16" smd rect
			(at -24.5 3.1 90)
			(size 0.53 2)
			(layers "F.Cu" "F.Mask" "F.Paste")
			(net 66 "GND")
			(pinfunction "B16")
			(pintype "passive")
		)
		(pad "B17" smd rect
			(at -23.5 3.1 90)
			(size 0.53 2)
			(layers "F.Cu" "F.Mask" "F.Paste")
			(net 7 "unconnected-(J2-PadB17)")
			(pinfunction "B17")
			(pintype "passive+no_connect")
		)
		(pad "B18" smd rect
			(at -22.5 3.1 90)
			(size 0.53 2)
			(layers "F.Cu" "F.Mask" "F.Paste")
			(net 66 "GND")
			(pinfunction "B18")
			(pintype "passive")
		)
		(pad "B19" smd rect
			(at -21.5 3.1 90)
			(size 0.53 2)
			(layers "F.Cu" "F.Mask" "F.Paste")
			(net 77 "/OCuLink/PCIe_{x4}.TX1+")
			(pinfunction "B19")
			(pintype "passive")
		)
		(pad "B20" smd rect
			(at -20.5 3.1 90)
			(size 0.53 2)
			(layers "F.Cu" "F.Mask" "F.Paste")
			(net 69 "/OCuLink/PCIe_{x4}.TX1-")
			(pinfunction "B20")
			(pintype "passive")
		)
		(pad "B21" smd rect
			(at -19.5 3.1 90)
			(size 0.53 2)
			(layers "F.Cu" "F.Mask" "F.Paste")
			(net 66 "GND")
			(pinfunction "B21")
			(pintype "passive")
		)
		(pad "B22" smd rect
			(at -18.5 3.1 90)
			(size 0.53 2)
			(layers "F.Cu" "F.Mask" "F.Paste")
			(net 66 "GND")
			(pinfunction "B22")
			(pintype "passive")
		)
		(pad "B23" smd rect
			(at -17.5 3.1 90)
			(size 0.53 2)
			(layers "F.Cu" "F.Mask" "F.Paste")
			(net 70 "/OCuLink/PCIe_{x4}.TX2+")
			(pinfunction "B23")
			(pintype "passive")
		)
		(pad "B24" smd rect
			(at -16.5 3.1 90)
			(size 0.53 2)
			(layers "F.Cu" "F.Mask" "F.Paste")
			(net 76 "/OCuLink/PCIe_{x4}.TX2-")
			(pinfunction "B24")
			(pintype "passive")
		)
		(pad "B25" smd rect
			(at -15.501 3.1 90)
			(size 0.53 2)
			(layers "F.Cu" "F.Mask" "F.Paste")
			(net 66 "GND")
			(pinfunction "B25")
			(pintype "passive")
		)
		(pad "B26" smd rect
			(at -14.501 3.1 90)
			(size 0.53 2)
			(layers "F.Cu" "F.Mask" "F.Paste")
			(net 66 "GND")
			(pinfunction "B26")
			(pintype "passive")
		)
		(pad "B27" smd rect
			(at -13.501 3.1 90)
			(size 0.53 2)
			(layers "F.Cu" "F.Mask" "F.Paste")
			(net 82 "/OCuLink/PCIe_{x4}.TX3+")
			(pinfunction "B27")
			(pintype "passive")
		)
		(pad "B28" smd rect
			(at -12.501 3.1 90)
			(size 0.53 2)
			(layers "F.Cu" "F.Mask" "F.Paste")
			(net 80 "/OCuLink/PCIe_{x4}.TX3-")
			(pinfunction "B28")
			(pintype "passive")
		)
		(pad "B29" smd rect
			(at -11.501 3.1 90)
			(size 0.53 2)
			(layers "F.Cu" "F.Mask" "F.Paste")
			(net 66 "GND")
			(pinfunction "B29")
			(pintype "passive")
		)
		(pad "B30" smd rect
			(at -10.501 3.1 90)
			(size 0.53 2)
			(layers "F.Cu" "F.Mask" "F.Paste")
			(net 54 "unconnected-(J2-PadB30)")
			(pinfunction "B30")
			(pintype "passive+no_connect")
		)
		(pad "B31" smd rect
			(at -9.501 3.1 90)
			(size 0.53 2)
			(layers "F.Cu" "F.Mask" "F.Paste")
			(net 10 "unconnected-(J2-PadB31)")
			(pinfunction "B31")
			(pintype "passive+no_connect")
		)
		(pad "B32" smd rect
			(at -8.501 3.1 90)
			(size 0.53 2)
			(layers "F.Cu" "F.Mask" "F.Paste")
			(net 66 "GND")
			(pinfunction "B32")
			(pintype "passive")
		)
		(pad "B33" smd rect
			(at -7.502 3.1 90)
			(size 0.53 2)
			(layers "F.Cu" "F.Mask" "F.Paste")
			(net 5 "unconnected-(J2-PadB33)")
			(pinfunction "B33")
			(pintype "passive+no_connect")
		)
		(pad "B34" smd rect
			(at -6.502 3.1 90)
			(size 0.53 2)
			(layers "F.Cu" "F.Mask" "F.Paste")
			(net 41 "unconnected-(J2-PadB34)")
			(pinfunction "B34")
			(pintype "passive+no_connect")
		)
		(pad "B35" smd rect
			(at -5.502 3.1 90)
			(size 0.53 2)
			(layers "F.Cu" "F.Mask" "F.Paste")
			(net 66 "GND")
			(pinfunction "B35")
			(pintype "passive")
		)
		(pad "B36" smd rect
			(at -4.502 3.1 90)
			(size 0.53 2)
			(layers "F.Cu" "F.Mask" "F.Paste")
			(net 66 "GND")
			(pinfunction "B36")
			(pintype "passive")
		)
		(pad "B37" smd rect
			(at -3.501 3.1 90)
			(size 0.53 2)
			(layers "F.Cu" "F.Mask" "F.Paste")
			(net 44 "unconnected-(J2-PadB37)")
			(pinfunction "B37")
			(pintype "passive+no_connect")
		)
		(pad "B38" smd rect
			(at -2.501 3.1 90)
			(size 0.53 2)
			(layers "F.Cu" "F.Mask" "F.Paste")
			(net 11 "unconnected-(J2-PadB38)")
			(pinfunction "B38")
			(pintype "passive+no_connect")
		)
		(pad "B39" smd rect
			(at -1.502 3.1 90)
			(size 0.53 2)
			(layers "F.Cu" "F.Mask" "F.Paste")
			(net 66 "GND")
			(pinfunction "B39")
			(pintype "passive")
		)
		(pad "B40" smd rect
			(at -0.501 3.1 90)
			(size 0.53 2)
			(layers "F.Cu" "F.Mask" "F.Paste")
			(net 66 "GND")
			(pinfunction "B40")
			(pintype "passive")
		)
		(pad "B41" smd rect
			(at 0.498 3.1 90)
			(size 0.53 2)
			(layers "F.Cu" "F.Mask" "F.Paste")
			(net 46 "unconnected-(J2-PadB41)")
			(pinfunction "B41")
			(pintype "passive+no_connect")
		)
		(pad "B42" smd rect
			(at 1.499 3.1 90)
			(size 0.53 2)
			(layers "F.Cu" "F.Mask" "F.Paste")
			(net 58 "unconnected-(J2-PadB42)")
			(pinfunction "B42")
			(pintype "passive+no_connect")
		)
		(pad "B43" smd rect
			(at 2.499 3.1 90)
			(size 0.53 2)
			(layers "F.Cu" "F.Mask" "F.Paste")
			(net 66 "GND")
			(pinfunction "B43")
			(pintype "passive")
		)
		(pad "B44" smd rect
			(at 3.499 3.1 90)
			(size 0.53 2)
			(layers "F.Cu" "F.Mask" "F.Paste")
			(net 66 "GND")
			(pinfunction "B44")
			(pintype "passive")
		)
		(pad "B45" smd rect
			(at 4.498 3.1 90)
			(size 0.53 2)
			(layers "F.Cu" "F.Mask" "F.Paste")
			(net 65 "unconnected-(J2-PadB45)")
			(pinfunction "B45")
			(pintype "passive+no_connect")
		)
		(pad "B46" smd rect
			(at 5.499 3.1 90)
			(size 0.53 2)
			(layers "F.Cu" "F.Mask" "F.Paste")
			(net 15 "unconnected-(J2-PadB46)")
			(pinfunction "B46")
			(pintype "passive+no_connect")
		)
		(pad "B47" smd rect
			(at 6.499 3.1 90)
			(size 0.53 2)
			(layers "F.Cu" "F.Mask" "F.Paste")
			(net 66 "GND")
			(pinfunction "B47")
			(pintype "passive")
		)
		(pad "B48" smd rect
			(at 7.499 3.1 90)
			(size 0.53 2)
			(layers "F.Cu" "F.Mask" "F.Paste")
			(net 43 "unconnected-(J2-PadB48)")
			(pinfunction "B48")
			(pintype "passive+no_connect")
		)
		(pad "B49" smd rect
			(at 8.499 3.1 90)
			(size 0.53 2)
			(layers "F.Cu" "F.Mask" "F.Paste")
			(net 66 "GND")
			(pinfunction "B49")
			(pintype "passive")
		)
		(pad "B50" smd rect
			(at 9.499 3.1 90)
			(size 0.53 2)
			(layers "F.Cu" "F.Mask" "F.Paste")
			(net 35 "unconnected-(J2-PadB50)")
			(pinfunction "B50")
			(pintype "passive+no_connect")
		)
		(pad "B51" smd rect
			(at 10.499 3.1 90)
			(size 0.53 2)
			(layers "F.Cu" "F.Mask" "F.Paste")
			(net 31 "unconnected-(J2-PadB51)")
			(pinfunction "B51")
			(pintype "passive+no_connect")
		)
		(pad "B52" smd rect
			(at 11.499 3.1 90)
			(size 0.53 2)
			(layers "F.Cu" "F.Mask" "F.Paste")
			(net 66 "GND")
			(pinfunction "B52")
			(pintype "passive")
		)
		(pad "B53" smd rect
			(at 12.499 3.1 90)
			(size 0.53 2)
			(layers "F.Cu" "F.Mask" "F.Paste")
			(net 66 "GND")
			(pinfunction "B53")
			(pintype "passive")
		)
		(pad "B54" smd rect
			(at 13.499 3.1 90)
			(size 0.53 2)
			(layers "F.Cu" "F.Mask" "F.Paste")
			(net 33 "unconnected-(J2-PadB54)")
			(pinfunction "B54")
			(pintype "passive+no_connect")
		)
		(pad "B55" smd rect
			(at 14.499 3.1 90)
			(size 0.53 2)
			(layers "F.Cu" "F.Mask" "F.Paste")
			(net 9 "unconnected-(J2-PadB55)")
			(pinfunction "B55")
			(pintype "passive+no_connect")
		)
		(pad "B56" smd rect
			(at 15.499 3.1 90)
			(size 0.53 2)
			(layers "F.Cu" "F.Mask" "F.Paste")
			(net 66 "GND")
			(pinfunction "B56")
			(pintype "passive")
		)
		(pad "B57" smd rect
			(at 16.498 3.1 90)
			(size 0.53 2)
			(layers "F.Cu" "F.Mask" "F.Paste")
			(net 66 "GND")
			(pinfunction "B57")
			(pintype "passive")
		)
		(pad "B58" smd rect
			(at 17.498 3.1 90)
			(size 0.53 2)
			(layers "F.Cu" "F.Mask" "F.Paste")
			(net 56 "unconnected-(J2-PadB58)")
			(pinfunction "B58")
			(pintype "passive+no_connect")
		)
		(pad "B59" smd rect
			(at 18.498 3.1 90)
			(size 0.53 2)
			(layers "F.Cu" "F.Mask" "F.Paste")
			(net 63 "unconnected-(J2-PadB59)")
			(pinfunction "B59")
			(pintype "passive+no_connect")
		)
		(pad "B60" smd rect
			(at 19.498 3.1 90)
			(size 0.53 2)
			(layers "F.Cu" "F.Mask" "F.Paste")
			(net 66 "GND")
			(pinfunction "B60")
			(pintype "passive")
		)
		(pad "B61" smd rect
			(at 20.498 3.1 90)
			(size 0.53 2)
			(layers "F.Cu" "F.Mask" "F.Paste")
			(net 66 "GND")
			(pinfunction "B61")
			(pintype "passive")
		)
		(pad "B62" smd rect
			(at 21.498 3.1 90)
			(size 0.53 2)
			(layers "F.Cu" "F.Mask" "F.Paste")
			(net 17 "unconnected-(J2-PadB62)")
			(pinfunction "B62")
			(pintype "passive+no_connect")
		)
		(pad "B63" smd rect
			(at 22.498 3.1 90)
			(size 0.53 2)
			(layers "F.Cu" "F.Mask" "F.Paste")
			(net 51 "unconnected-(J2-PadB63)")
			(pinfunction "B63")
			(pintype "passive+no_connect")
		)
		(pad "B64" smd rect
			(at 23.498 3.1 90)
			(size 0.53 2)
			(layers "F.Cu" "F.Mask" "F.Paste")
			(net 66 "GND")
			(pinfunction "B64")
			(pintype "passive")
		)
		(pad "B65" smd rect
			(at 24.498 3.1 90)
			(size 0.53 2)
			(layers "F.Cu" "F.Mask" "F.Paste")
			(net 66 "GND")
			(pinfunction "B65")
			(pintype "passive")
		)
		(pad "B66" smd rect
			(at 25.498 3.1 90)
			(size 0.53 2)
			(layers "F.Cu" "F.Mask" "F.Paste")
			(net 34 "unconnected-(J2-PadB66)")
			(pinfunction "B66")
			(pintype "passive+no_connect")
		)
		(pad "B67" smd rect
			(at 26.498 3.1 90)
			(size 0.53 2)
			(layers "F.Cu" "F.Mask" "F.Paste")
			(net 52 "unconnected-(J2-PadB67)")
			(pinfunction "B67")
			(pintype "passive+no_connect")
		)
		(pad "B68" smd rect
			(at 27.499 3.1 90)
			(size 0.53 2)
			(layers "F.Cu" "F.Mask" "F.Paste")
			(net 66 "GND")
			(pinfunction "B68")
			(pintype "passive")
		)
		(pad "B69" smd rect
			(at 28.499 3.1 90)
			(size 0.53 2)
			(layers "F.Cu" "F.Mask" "F.Paste")
			(net 66 "GND")
			(pinfunction "B69")
			(pintype "passive")
		)
		(pad "B70" smd rect
			(at 29.499 3.1 90)
			(size 0.53 2)
			(layers "F.Cu" "F.Mask" "F.Paste")
			(net 4 "unconnected-(J2-PadB70)")
			(pinfunction "B70")
			(pintype "passive+no_connect")
		)
		(pad "B71" smd rect
			(at 30.499 3.1 90)
			(size 0.53 2)
			(layers "F.Cu" "F.Mask" "F.Paste")
			(net 42 "unconnected-(J2-PadB71)")
			(pinfunction "B71")
			(pintype "passive+no_connect")
		)
		(pad "B72" smd rect
			(at 31.499 3.1 90)
			(size 0.53 2)
			(layers "F.Cu" "F.Mask" "F.Paste")
			(net 66 "GND")
			(pinfunction "B72")
			(pintype "passive")
		)
		(pad "B73" smd rect
			(at 32.499 3.1 90)
			(size 0.53 2)
			(layers "F.Cu" "F.Mask" "F.Paste")
			(net 66 "GND")
			(pinfunction "B73")
			(pintype "passive")
		)
		(pad "B74" smd rect
			(at 33.499 3.1 90)
			(size 0.53 2)
			(layers "F.Cu" "F.Mask" "F.Paste")
			(net 22 "unconnected-(J2-PadB74)")
			(pinfunction "B74")
			(pintype "passive+no_connect")
		)
		(pad "B75" smd rect
			(at 34.499 3.1 90)
			(size 0.53 2)
			(layers "F.Cu" "F.Mask" "F.Paste")
			(net 60 "unconnected-(J2-PadB75)")
			(pinfunction "B75")
			(pintype "passive+no_connect")
		)
		(pad "B76" smd rect
			(at 35.499 3.1 90)
			(size 0.53 2)
			(layers "F.Cu" "F.Mask" "F.Paste")
			(net 66 "GND")
			(pinfunction "B76")
			(pintype "passive")
		)
		(pad "B77" smd rect
			(at 36.499 3.1 90)
			(size 0.53 2)
			(layers "F.Cu" "F.Mask" "F.Paste")
			(net 66 "GND")
			(pinfunction "B77")
			(pintype "passive")
		)
		(pad "B78" smd rect
			(at 37.499 3.1 90)
			(size 0.53 2)
			(layers "F.Cu" "F.Mask" "F.Paste")
			(net 48 "unconnected-(J2-PadB78)")
			(pinfunction "B78")
			(pintype "passive+no_connect")
		)
		(pad "B79" smd rect
			(at 38.499 3.1 90)
			(size 0.53 2)
			(layers "F.Cu" "F.Mask" "F.Paste")
			(net 61 "unconnected-(J2-PadB79)")
			(pinfunction "B79")
			(pintype "passive+no_connect")
		)
		(pad "B80" smd rect
			(at 39.499 3.1 90)
			(size 0.53 2)
			(layers "F.Cu" "F.Mask" "F.Paste")
			(net 66 "GND")
			(pinfunction "B80")
			(pintype "passive")
		)
		(pad "B81" smd rect
			(at 40.499 3.1 90)
			(size 0.53 2)
			(layers "F.Cu" "F.Mask" "F.Paste")
			(net 25 "unconnected-(J2-PadB81)")
			(pinfunction "B81")
			(pintype "passive+no_connect")
		)
		(pad "B82" smd rect
			(at 41.499 3.1 90)
			(size 0.53 2)
			(layers "F.Cu" "F.Mask" "F.Paste")
			(net 28 "unconnected-(J2-PadB82)")
			(pinfunction "B82")
			(pintype "passive+no_connect")
		)
		(pad "S1" smd rect
			(at -44.5 -0.5 90)
			(size 3 5)
			(layers "F.Cu" "F.Mask")
			(net 66 "GND")
			(pinfunction "S1")
			(pintype "passive")
		)
		(pad "S2" smd rect
			(at 44.6 -0.5005 90)
			(size 3 5)
			(layers "F.Cu" "F.Mask")
			(net 66 "GND")
			(pinfunction "S2")
			(pintype "passive")
		)
	)
)
